(kicad_pcb
	(version 20240108)
	(generator "pcbnew")
	(generator_version "8.0")
	(general
		(thickness 1.6)
		(legacy_teardrops no)
	)
	(paper "A4")
	(title_block
		(title "Jetson Orin Baseboard OCuLink Expansion")
		(date "2025-03-18")
		(rev "1.1.0")
		(company "Antmicro Ltd")
		(comment 1 "www.antmicro.com")
		(comment 9 "footprints 118-119 of 119")
	)
	(layers
		(0 "F.Cu" signal)
		(1 "In1.Cu" signal)
		(2 "In2.Cu" signal)
		(31 "B.Cu" signal)
		(32 "B.Adhes" user "B.Adhesive")
		(33 "F.Adhes" user "F.Adhesive")
		(34 "B.Paste" user)
		(35 "F.Paste" user)
		(36 "B.SilkS" user "B.Silkscreen")
		(37 "F.SilkS" user "F.Silkscreen")
		(38 "B.Mask" user)
		(39 "F.Mask" user)
		(40 "Dwgs.User" user "User.Drawings")
		(41 "Cmts.User" user "User.Comments")
		(42 "Eco1.User" user "User.Eco1")
		(43 "Eco2.User" user "User.Eco2")
		(44 "Edge.Cuts" user)
		(45 "Margin" user)
		(46 "B.CrtYd" user "B.Courtyard")
		(47 "F.CrtYd" user "F.Courtyard")
		(48 "B.Fab" user)
		(49 "F.Fab" user)
	)
	(footprint "antmicro-footprints:R_0402_1005Metric"
		(layer "B.Cu")
		(at 129.72 112.85)
		(descr "Resistor SMD 0402")
		(tags "resistor SMD 0402")
		(property "Reference" "R39"
			(at 0.66 -0.356249 0)
			(layer "B.SilkS")
			(effects
				(font
					(size 0.7 0.7)
					(thickness 0.15)
				)
				(justify right top mirror)
			)
		)
		(property "Value" "R_0R_0402"
			(at -1.011843 -1.772047 0)
			(layer "B.Fab")
			(effects
				(font
					(size 0.7 0.7)
					(thickness 0.15)
				)
				(justify right top mirror)
			)
		)
		(property "Footprint" "antmicro-footprints:R_0402_1005Metric"
			(at 0 0 0)
			(layer "B.Fab")
			(hide yes)
			(effects
				(font
					(size 1.27 1.27)
					(thickness 0.15)
				)
				(justify mirror)
			)
		)
		(property "Datasheet" "https://industrial.panasonic.com/cdbs/www-data/pdf/RDA0000/AOA0000C301.pdf"
			(at 0 0 0)
			(layer "B.Fab")
			(hide yes)
			(effects
				(font
					(size 1.27 1.27)
					(thickness 0.15)
				)
				(justify mirror)
			)
		)
		(property "Description" "SMD Chip Resistor, Jumper, 0 ohm, 100 mW, 0402 [1005 Metric], Thick Film, General Purpose"
			(at 0 0 0)
			(layer "B.Fab")
			(hide yes)
			(effects
				(font
					(size 1.27 1.27)
					(thickness 0.15)
				)
				(justify mirror)
			)
		)
		(property "MPN" "ERJ2GE0R00X"
			(at 0 0 180)
			(unlocked yes)
			(layer "B.Fab")
			(hide yes)
			(effects
				(font
					(size 1 1)
					(thickness 0.15)
				)
				(justify mirror)
			)
		)
		(property "Manufacturer" "Panasonic"
			(at 0 0 180)
			(unlocked yes)
			(layer "B.Fab")
			(hide yes)
			(effects
				(font
					(size 1 1)
					(thickness 0.15)
				)
				(justify mirror)
			)
		)
		(property "License" "Apache-2.0"
			(at 0 0 180)
			(unlocked yes)
			(layer "B.Fab")
			(hide yes)
			(effects
				(font
					(size 1 1)
					(thickness 0.15)
				)
				(justify mirror)
			)
		)
		(property "Author" "Antmicro"
			(at 0 0 180)
			(unlocked yes)
			(layer "B.Fab")
			(hide yes)
			(effects
				(font
					(size 1 1)
					(thickness 0.15)
				)
				(justify mirror)
			)
		)
		(property "Val" "0R"
			(at 0 0 180)
			(unlocked yes)
			(layer "B.Fab")
			(hide yes)
			(effects
				(font
					(size 1 1)
					(thickness 0.15)
				)
				(justify mirror)
			)
		)
		(property "Tolerance" ""
			(at 0 0 180)
			(unlocked yes)
			(layer "B.Fab")
			(hide yes)
			(effects
				(font
					(size 1 1)
					(thickness 0.15)
				)
				(justify mirror)
			)
		)
		(property "Current" "1A"
			(at 0 0 180)
			(unlocked yes)
			(layer "B.Fab")
			(hide yes)
			(effects
				(font
					(size 1 1)
					(thickness 0.15)
				)
				(justify mirror)
			)
		)
		(property "Public" "False"
			(at 0 0 180)
			(unlocked yes)
			(layer "B.Fab")
			(hide yes)
			(effects
				(font
					(size 1 1)
					(thickness 0.15)
				)
				(justify mirror)
			)
		)
		(sheetname "Root")
		(sheetfile "jetson-orin-baseboard-oculink-expansion.kicad_sch")
		(attr smd dnp)
		(fp_rect
			(start -0.925 0.47)
			(end 0.925 -0.47)
			(stroke
				(width 0.05)
				(type default)
			)
			(fill none)
			(layer "B.CrtYd")
		)
		(fp_rect
			(start -0.5 0.25)
			(end 0.5 -0.25)
			(stroke
				(width 0.15)
				(type solid)
			)
			(fill none)
			(layer "B.Fab")
		)
		(fp_text user "${REFERENCE}"
			(at -0.95 -3.168 0)
			(layer "B.Fab")
			(hide yes)
			(effects
				(font
					(size 0.7 0.7)
					(thickness 0.15)
				)
				(justify right top mirror)
			)
		)
		(fp_text user "Author: Antmicro"
			(at -0.95 -4.169 0)
			(layer "B.Fab")
			(hide yes)
			(effects
				(font
					(size 0.7 0.7)
					(thickness 0.15)
				)
				(justify right top mirror)
			)
		)
		(fp_text user "License: Apache-2.0"
			(at -0.95 -5.169 0)
			(layer "B.Fab")
			(hide yes)
			(effects
				(font
					(size 0.7 0.7)
					(thickness 0.15)
				)
				(justify right top mirror)
			)
		)
		(pad "1" smd roundrect
			(at -0.48 0)
			(size 0.59 0.64)
			(layers "B.Cu" "B.Paste" "B.Mask")
			(roundrect_rratio 0.25)
			(net 23 "+3V3")
			(pintype "passive")
		)
		(pad "2" smd roundrect
			(at 0.48 0)
			(size 0.59 0.64)
			(layers "B.Cu" "B.Paste" "B.Mask")
			(roundrect_rratio 0.25)
			(net 103 "Net-(U2-EN_{I2C})")
			(pintype "passive")
		)
	)
	(footprint "antmicro-footprints:R_0402_1005Metric"
		(layer "B.Cu")
		(at 116.475 112.433751)
		(descr "Resistor SMD 0402")
		(tags "resistor SMD 0402")
		(property "Reference" "R13"
			(at -3.251667 -0.383751 0)
			(layer "B.SilkS")
			(effects
				(font
					(size 0.7 0.7)
					(thickness 0.15)
				)
				(justify right top mirror)
			)
		)
		(property "Value" "R_1k_0402"
			(at -1.011843 -1.772047 0)
			(layer "B.Fab")
			(effects
				(font
					(size 0.7 0.7)
					(thickness 0.15)
				)
				(justify right top mirror)
			)
		)
		(property "Footprint" "antmicro-footprints:R_0402_1005Metric"
			(at 0 0 0)
			(layer "B.Fab")
			(hide yes)
			(effects
				(font
					(size 1.27 1.27)
					(thickness 0.15)
				)
				(justify mirror)
			)
		)
		(property "Datasheet" "https://www.bourns.com/docs/product-datasheets/cr.pdf"
			(at 0 0 0)
			(layer "B.Fab")
			(hide yes)
			(effects
				(font
					(size 1.27 1.27)
					(thickness 0.15)
				)
				(justify mirror)
			)
		)
		(property "Description" "SMD Chip Resistor, 1 kohm, ± 1%, 63 mW, 0402 [1005 Metric], Thick Film, General Purpose"
			(at 0 0 0)
			(layer "B.Fab")
			(hide yes)
			(effects
				(font
					(size 1.27 1.27)
					(thickness 0.15)
				)
				(justify mirror)
			)
		)
		(property "MPN" "CR0402-FX-1001GLF"
			(at 0 0 180)
			(unlocked yes)
			(layer "B.Fab")
			(hide yes)
			(effects
				(font
					(size 1 1)
					(thickness 0.15)
				)
				(justify mirror)
			)
		)
		(property "Manufacturer" "Bourns"
			(at 0 0 180)
			(unlocked yes)
			(layer "B.Fab")
			(hide yes)
			(effects
				(font
					(size 1 1)
					(thickness 0.15)
				)
				(justify mirror)
			)
		)
		(property "License" "Apache-2.0"
			(at 0 0 180)
			(unlocked yes)
			(layer "B.Fab")
			(hide yes)
			(effects
				(font
					(size 1 1)
					(thickness 0.15)
				)
				(justify mirror)
			)
		)
		(property "Author" "Antmicro"
			(at 0 0 180)
			(unlocked yes)
			(layer "B.Fab")
			(hide yes)
			(effects
				(font
					(size 1 1)
					(thickness 0.15)
				)
				(justify mirror)
			)
		)
		(property "Val" "1k"
			(at 0 0 180)
			(unlocked yes)
			(layer "B.Fab")
			(hide yes)
			(effects
				(font
					(size 1 1)
					(thickness 0.15)
				)
				(justify mirror)
			)
		)
		(property "Tolerance" "1%"
			(at 0 0 180)
			(unlocked yes)
			(layer "B.Fab")
			(hide yes)
			(effects
				(font
					(size 1 1)
					(thickness 0.15)
				)
				(justify mirror)
			)
		)
		(property "Public" "False"
			(at 0 0 180)
			(unlocked yes)
			(layer "B.Fab")
			(hide yes)
			(effects
				(font
					(size 1 1)
					(thickness 0.15)
				)
				(justify mirror)
			)
		)
		(sheetname "Root")
		(sheetfile "jetson-orin-baseboard-oculink-expansion.kicad_sch")
		(attr smd dnp)
		(fp_rect
			(start -0.925 0.47)
			(end 0.925 -0.47)
			(stroke
				(width 0.05)
				(type default)
			)
			(fill none)
			(layer "B.CrtYd")
		)
		(fp_rect
			(start -0.5 0.25)
			(end 0.5 -0.25)
			(stroke
				(width 0.15)
				(type solid)
			)
			(fill none)
			(layer "B.Fab")
		)
		(fp_text user "License: Apache-2.0"
			(at -0.95 -5.169 0)
			(layer "B.Fab")
			(hide yes)
			(effects
				(font
					(size 0.7 0.7)
					(thickness 0.15)
				)
				(justify right top mirror)
			)
		)
		(fp_text user "${REFERENCE}"
			(at -0.95 -3.168 0)
			(layer "B.Fab")
			(hide yes)
			(effects
				(font
					(size 0.7 0.7)
					(thickness 0.15)
				)
				(justify right top mirror)
			)
		)
		(fp_text user "Author: Antmicro"
			(at -0.95 -4.169 0)
			(layer "B.Fab")
			(hide yes)
			(effects
				(font
					(size 0.7 0.7)
					(thickness 0.15)
				)
				(justify right top mirror)
			)
		)
		(pad "1" smd roundrect
			(at -0.48 0)
			(size 0.59 0.64)
			(layers "B.Cu" "B.Paste" "B.Mask")
			(roundrect_rratio 0.25)
			(net 51 "GND")
			(pintype "passive")
		)
		(pad "2" smd roundrect
			(at 0.48 0)
			(size 0.59 0.64)
			(layers "B.Cu" "B.Paste" "B.Mask")
			(roundrect_rratio 0.25)
			(net 93 "/RX_FG1")
			(pintype "passive")
		)
	)
)
